(kicad_pcb
	(version 20221018)
	(generator pcbnew)
	(general
    (thickness 1.62)
  )
	(paper "A4")
	(title_block
    (title "ECP5 - Datacenter Secure Control Module (DC-SCM)")
    (date "2024-07-01")
    (rev "1.2.1")
		(comment 9 "footprints 25-29 of 506")
	)
	(layers
    (0 "F.Cu" signal)
    (1 "In1.Cu" power)
    (2 "In2.Cu" signal)
    (3 "In3.Cu" power)
    (4 "In4.Cu" power)
    (5 "In5.Cu" signal)
    (6 "In6.Cu" power)
    (31 "B.Cu" signal)
    (32 "B.Adhes" user "B.Adhesive")
    (33 "F.Adhes" user "F.Adhesive")
    (34 "B.Paste" user)
    (35 "F.Paste" user)
    (36 "B.SilkS" user "B.Silkscreen")
    (37 "F.SilkS" user "F.Silkscreen")
    (38 "B.Mask" user)
    (39 "F.Mask" user)
    (40 "Dwgs.User" user "User.Drawings")
    (41 "Cmts.User" user "User.Comments")
    (42 "Eco1.User" user "User.Eco1")
    (43 "Eco2.User" user "User.Eco2")
    (44 "Edge.Cuts" user)
    (45 "Margin" user)
    (46 "B.CrtYd" user "B.Courtyard")
    (47 "F.CrtYd" user "F.Courtyard")
    (48 "B.Fab" user)
    (49 "F.Fab" user)
  )
	(footprint "antmicro-footprints:LED_0603_1608Metric_G" (layer "F.Cu")
    (at 65.5 85.891666 180)
    (descr "LED SMD 0603 Green")
    (tags "LED SMD 0603 Green")
    (property "Author" "Antmicro")
    (property "Color" "Green")
    (property "License" "Apache-2.0")
    (property "MPN" "LG L29K-G2J1-24-Z")
    (property "Manufacturer" "OSRAM")
    (property "Sheetfile" "power-supply.kicad_sch")
    (property "Sheetname" "Power supply")
    (property "ki_description" "LED, Green, SMD, 0603, 20 mA, 1.7 V, 570 nm")
    (property "ki_keywords" "SMT, DIODE, SEMICONDUCTOR, LED")
    (attr smd)
    (fp_text reference "D7" (at 1.8 0.741666 90) (layer "F.SilkS")
        (effects (font (size 0.7 0.7) (thickness 0.127)))
    )
    (fp_text value "LED_G_0603_LG_L29K-G2J1-24-Z" (at 0 1.77) (layer "F.Fab")
        (effects (font (size 1 1) (thickness 0.15)))
    )
    (fp_text user "${REFERENCE}" (at -1.4224 5.999 180) (layer "F.Fab") hide
        (effects (font (size 0.7 0.7) (thickness 0.15)) (justify left bottom))
    )
    (fp_text user "License: Apache-2.0" (at -1.4224 3.599 180) (layer "F.Fab") hide
        (effects (font (size 0.7 0.7) (thickness 0.15)) (justify left bottom))
    )
    (fp_text user "Author: Antmicro" (at -1.4224 4.799 180) (layer "F.Fab") hide
        (effects (font (size 0.7 0.7) (thickness 0.15)) (justify left bottom))
    )
    (fp_line (start -1.18 -0.319) (end -1.18 0.321)
      (stroke (width 0.15) (type solid)) (layer "F.SilkS"))
    (fp_line (start -0.094672 0.001008) (end -0.24 0.001008)
      (stroke (width 0.1) (type solid)) (layer "F.SilkS"))
    (fp_line (start -0.094672 0.001008) (end 0.105328 -0.198992)
      (stroke (width 0.1) (type solid)) (layer "F.SilkS"))
    (fp_line (start -0.094672 0.201008) (end -0.094672 -0.198992)
      (stroke (width 0.1) (type solid)) (layer "F.SilkS"))
    (fp_line (start 0.105328 0.001008) (end 0.24 0.001)
      (stroke (width 0.1) (type solid)) (layer "F.SilkS"))
    (fp_line (start 0.105328 0.201008) (end -0.094672 0.001008)
      (stroke (width 0.1) (type solid)) (layer "F.SilkS"))
    (fp_line (start 0.105328 0.201008) (end 0.105328 -0.198992)
      (stroke (width 0.1) (type solid)) (layer "F.SilkS"))
    (fp_line (start 0.22 -0.35) (end -0.22 -0.35)
      (stroke (width 0.15) (type solid)) (layer "F.SilkS"))
    (fp_line (start 0.22 0.35) (end -0.22 0.35)
      (stroke (width 0.15) (type solid)) (layer "F.SilkS"))
    (fp_rect (start 1.25 0.65) (end -1.25 -0.65)
      (stroke (width 0.05) (type solid)) (fill none) (layer "F.CrtYd"))
    (fp_line (start -0.199 -0.202) (end -0.199 0.1)
      (stroke (width 0.15) (type solid)) (layer "F.Fab"))
    (fp_line (start -0.199 0) (end -0.597 0)
      (stroke (width 0.15) (type solid)) (layer "F.Fab"))
    (fp_line (start -0.199 0.2) (end -0.199 0.1)
      (stroke (width 0.15) (type solid)) (layer "F.Fab"))
    (fp_line (start -0.101 0) (end 0.201 0.2)
      (stroke (width 0.15) (type solid)) (layer "F.Fab"))
    (fp_line (start 0.201 -0.202) (end -0.101 0)
      (stroke (width 0.15) (type solid)) (layer "F.Fab"))
    (fp_line (start 0.201 0) (end 0.201 -0.202)
      (stroke (width 0.15) (type solid)) (layer "F.Fab"))
    (fp_line (start 0.201 0.2) (end 0.201 0)
      (stroke (width 0.15) (type solid)) (layer "F.Fab"))
    (fp_line (start 0.599 0) (end 0.201 0)
      (stroke (width 0.15) (type solid)) (layer "F.Fab"))
    (fp_rect (start 0.848 0.4) (end -0.85 -0.402)
      (stroke (width 0.15) (type solid)) (fill none) (layer "F.Fab"))
    (pad "1" smd roundrect (at -0.7 0) (size 0.8 1) (layers "F.Cu" "F.Paste" "F.Mask") (roundrect_rratio 0.2)
      (net 2 "VCC3V3") (pinfunction "C") (pintype "passive"))
    (pad "2" smd roundrect (at 0.7 0) (size 0.8 1) (layers "F.Cu" "F.Paste" "F.Mask") (roundrect_rratio 0.2)
      (net 315 "Net-(D7-A)") (pinfunction "A") (pintype "passive"))
  )
	(footprint "antmicro-footprints:LED_0603_1608Metric_G" (layer "F.Cu")
    (at 65.5 84.25 180)
    (descr "LED SMD 0603 Green")
    (tags "LED SMD 0603 Green")
    (property "Author" "Antmicro")
    (property "Color" "Green")
    (property "License" "Apache-2.0")
    (property "MPN" "LG L29K-G2J1-24-Z")
    (property "Manufacturer" "OSRAM")
    (property "Sheetfile" "power-supply.kicad_sch")
    (property "Sheetname" "Power supply")
    (property "ki_description" "LED, Green, SMD, 0603, 20 mA, 1.7 V, 570 nm")
    (property "ki_keywords" "SMT, DIODE, SEMICONDUCTOR, LED")
    (attr smd)
    (fp_text reference "D8" (at 1.8 0.6 90) (layer "F.SilkS")
        (effects (font (size 0.7 0.7) (thickness 0.127)))
    )
    (fp_text value "LED_G_0603_LG_L29K-G2J1-24-Z" (at 0 1.77) (layer "F.Fab")
        (effects (font (size 1 1) (thickness 0.15)))
    )
    (fp_text user "License: Apache-2.0" (at -1.4224 3.599 180) (layer "F.Fab") hide
        (effects (font (size 0.7 0.7) (thickness 0.15)) (justify left bottom))
    )
    (fp_text user "${REFERENCE}" (at -1.4224 5.999 180) (layer "F.Fab") hide
        (effects (font (size 0.7 0.7) (thickness 0.15)) (justify left bottom))
    )
    (fp_text user "Author: Antmicro" (at -1.4224 4.799 180) (layer "F.Fab") hide
        (effects (font (size 0.7 0.7) (thickness 0.15)) (justify left bottom))
    )
    (fp_line (start -1.18 -0.319) (end -1.18 0.321)
      (stroke (width 0.15) (type solid)) (layer "F.SilkS"))
    (fp_line (start -0.094672 0.001008) (end -0.24 0.001008)
      (stroke (width 0.1) (type solid)) (layer "F.SilkS"))
    (fp_line (start -0.094672 0.001008) (end 0.105328 -0.198992)
      (stroke (width 0.1) (type solid)) (layer "F.SilkS"))
    (fp_line (start -0.094672 0.201008) (end -0.094672 -0.198992)
      (stroke (width 0.1) (type solid)) (layer "F.SilkS"))
    (fp_line (start 0.105328 0.001008) (end 0.24 0.001)
      (stroke (width 0.1) (type solid)) (layer "F.SilkS"))
    (fp_line (start 0.105328 0.201008) (end -0.094672 0.001008)
      (stroke (width 0.1) (type solid)) (layer "F.SilkS"))
    (fp_line (start 0.105328 0.201008) (end 0.105328 -0.198992)
      (stroke (width 0.1) (type solid)) (layer "F.SilkS"))
    (fp_line (start 0.22 -0.35) (end -0.22 -0.35)
      (stroke (width 0.15) (type solid)) (layer "F.SilkS"))
    (fp_line (start 0.22 0.35) (end -0.22 0.35)
      (stroke (width 0.15) (type solid)) (layer "F.SilkS"))
    (fp_rect (start 1.25 0.65) (end -1.25 -0.65)
      (stroke (width 0.05) (type solid)) (fill none) (layer "F.CrtYd"))
    (fp_line (start -0.199 -0.202) (end -0.199 0.1)
      (stroke (width 0.15) (type solid)) (layer "F.Fab"))
    (fp_line (start -0.199 0) (end -0.597 0)
      (stroke (width 0.15) (type solid)) (layer "F.Fab"))
    (fp_line (start -0.199 0.2) (end -0.199 0.1)
      (stroke (width 0.15) (type solid)) (layer "F.Fab"))
    (fp_line (start -0.101 0) (end 0.201 0.2)
      (stroke (width 0.15) (type solid)) (layer "F.Fab"))
    (fp_line (start 0.201 -0.202) (end -0.101 0)
      (stroke (width 0.15) (type solid)) (layer "F.Fab"))
    (fp_line (start 0.201 0) (end 0.201 -0.202)
      (stroke (width 0.15) (type solid)) (layer "F.Fab"))
    (fp_line (start 0.201 0.2) (end 0.201 0)
      (stroke (width 0.15) (type solid)) (layer "F.Fab"))
    (fp_line (start 0.599 0) (end 0.201 0)
      (stroke (width 0.15) (type solid)) (layer "F.Fab"))
    (fp_rect (start 0.848 0.4) (end -0.85 -0.402)
      (stroke (width 0.15) (type solid)) (fill none) (layer "F.Fab"))
    (pad "1" smd roundrect (at -0.7 0) (size 0.8 1) (layers "F.Cu" "F.Paste" "F.Mask") (roundrect_rratio 0.2)
      (net 2 "VCC3V3") (pinfunction "C") (pintype "passive"))
    (pad "2" smd roundrect (at 0.7 0) (size 0.8 1) (layers "F.Cu" "F.Paste" "F.Mask") (roundrect_rratio 0.2)
      (net 316 "Net-(D8-A)") (pinfunction "A") (pintype "passive"))
  )
	(footprint "antmicro-footprints:LED_0603_1608Metric_G" (layer "F.Cu")
    (at 65.5 94.1 180)
    (descr "LED SMD 0603 Green")
    (tags "LED SMD 0603 Green")
    (property "Author" "Antmicro")
    (property "Color" "Green")
    (property "License" "Apache-2.0")
    (property "MPN" "LG L29K-G2J1-24-Z")
    (property "Manufacturer" "OSRAM")
    (property "Sheetfile" "power-supply.kicad_sch")
    (property "Sheetname" "Power supply")
    (property "ki_description" "LED, Green, SMD, 0603, 20 mA, 1.7 V, 570 nm")
    (property "ki_keywords" "SMT, DIODE, SEMICONDUCTOR, LED")
    (attr smd)
    (fp_text reference "D9" (at 1.8 -0.95 90) (layer "F.SilkS")
        (effects (font (size 0.7 0.7) (thickness 0.127)))
    )
    (fp_text value "LED_G_0603_LG_L29K-G2J1-24-Z" (at 0 1.77) (layer "F.Fab")
        (effects (font (size 1 1) (thickness 0.15)))
    )
    (fp_text user "License: Apache-2.0" (at -1.4224 3.599 180) (layer "F.Fab") hide
        (effects (font (size 0.7 0.7) (thickness 0.15)) (justify left bottom))
    )
    (fp_text user "${REFERENCE}" (at -1.4224 5.999 180) (layer "F.Fab") hide
        (effects (font (size 0.7 0.7) (thickness 0.15)) (justify left bottom))
    )
    (fp_text user "Author: Antmicro" (at -1.4224 4.799 180) (layer "F.Fab") hide
        (effects (font (size 0.7 0.7) (thickness 0.15)) (justify left bottom))
    )
    (fp_line (start -1.18 -0.319) (end -1.18 0.321)
      (stroke (width 0.15) (type solid)) (layer "F.SilkS"))
    (fp_line (start -0.094672 0.001008) (end -0.24 0.001008)
      (stroke (width 0.1) (type solid)) (layer "F.SilkS"))
    (fp_line (start -0.094672 0.001008) (end 0.105328 -0.198992)
      (stroke (width 0.1) (type solid)) (layer "F.SilkS"))
    (fp_line (start -0.094672 0.201008) (end -0.094672 -0.198992)
      (stroke (width 0.1) (type solid)) (layer "F.SilkS"))
    (fp_line (start 0.105328 0.001008) (end 0.24 0.001)
      (stroke (width 0.1) (type solid)) (layer "F.SilkS"))
    (fp_line (start 0.105328 0.201008) (end -0.094672 0.001008)
      (stroke (width 0.1) (type solid)) (layer "F.SilkS"))
    (fp_line (start 0.105328 0.201008) (end 0.105328 -0.198992)
      (stroke (width 0.1) (type solid)) (layer "F.SilkS"))
    (fp_line (start 0.22 -0.35) (end -0.22 -0.35)
      (stroke (width 0.15) (type solid)) (layer "F.SilkS"))
    (fp_line (start 0.22 0.35) (end -0.22 0.35)
      (stroke (width 0.15) (type solid)) (layer "F.SilkS"))
    (fp_rect (start 1.25 0.65) (end -1.25 -0.65)
      (stroke (width 0.05) (type solid)) (fill none) (layer "F.CrtYd"))
    (fp_line (start -0.199 -0.202) (end -0.199 0.1)
      (stroke (width 0.15) (type solid)) (layer "F.Fab"))
    (fp_line (start -0.199 0) (end -0.597 0)
      (stroke (width 0.15) (type solid)) (layer "F.Fab"))
    (fp_line (start -0.199 0.2) (end -0.199 0.1)
      (stroke (width 0.15) (type solid)) (layer "F.Fab"))
    (fp_line (start -0.101 0) (end 0.201 0.2)
      (stroke (width 0.15) (type solid)) (layer "F.Fab"))
    (fp_line (start 0.201 -0.202) (end -0.101 0)
      (stroke (width 0.15) (type solid)) (layer "F.Fab"))
    (fp_line (start 0.201 0) (end 0.201 -0.202)
      (stroke (width 0.15) (type solid)) (layer "F.Fab"))
    (fp_line (start 0.201 0.2) (end 0.201 0)
      (stroke (width 0.15) (type solid)) (layer "F.Fab"))
    (fp_line (start 0.599 0) (end 0.201 0)
      (stroke (width 0.15) (type solid)) (layer "F.Fab"))
    (fp_rect (start 0.848 0.4) (end -0.85 -0.402)
      (stroke (width 0.15) (type solid)) (fill none) (layer "F.Fab"))
    (pad "1" smd roundrect (at -0.7 0) (size 0.8 1) (layers "F.Cu" "F.Paste" "F.Mask") (roundrect_rratio 0.2)
      (net 2 "VCC3V3") (pinfunction "C") (pintype "passive"))
    (pad "2" smd roundrect (at 0.7 0) (size 0.8 1) (layers "F.Cu" "F.Paste" "F.Mask") (roundrect_rratio 0.2)
      (net 343 "Net-(D9-A)") (pinfunction "A") (pintype "passive"))
  )
	(footprint "antmicro-footprints:LED_0603_1608Metric_G" (layer "F.Cu")
    (at 65.5 92.45833 180)
    (descr "LED SMD 0603 Green")
    (tags "LED SMD 0603 Green")
    (property "Author" "Antmicro")
    (property "Color" "Green")
    (property "License" "Apache-2.0")
    (property "MPN" "LG L29K-G2J1-24-Z")
    (property "Manufacturer" "OSRAM")
    (property "Sheetfile" "power-supply.kicad_sch")
    (property "Sheetname" "Power supply")
    (property "ki_description" "LED, Green, SMD, 0603, 20 mA, 1.7 V, 570 nm")
    (property "ki_keywords" "SMT, DIODE, SEMICONDUCTOR, LED")
    (attr smd)
    (fp_text reference "D10" (at 1.8 -0.64167 90) (layer "F.SilkS")
        (effects (font (size 0.7 0.7) (thickness 0.127)))
    )
    (fp_text value "LED_G_0603_LG_L29K-G2J1-24-Z" (at 0 1.77) (layer "F.Fab")
        (effects (font (size 1 1) (thickness 0.15)))
    )
    (fp_text user "License: Apache-2.0" (at -1.4224 3.599 180) (layer "F.Fab") hide
        (effects (font (size 0.7 0.7) (thickness 0.15)) (justify left bottom))
    )
    (fp_text user "${REFERENCE}" (at -1.4224 5.999 180) (layer "F.Fab") hide
        (effects (font (size 0.7 0.7) (thickness 0.15)) (justify left bottom))
    )
    (fp_text user "Author: Antmicro" (at -1.4224 4.799 180) (layer "F.Fab") hide
        (effects (font (size 0.7 0.7) (thickness 0.15)) (justify left bottom))
    )
    (fp_line (start -1.18 -0.319) (end -1.18 0.321)
      (stroke (width 0.15) (type solid)) (layer "F.SilkS"))
    (fp_line (start -0.094672 0.001008) (end -0.24 0.001008)
      (stroke (width 0.1) (type solid)) (layer "F.SilkS"))
    (fp_line (start -0.094672 0.001008) (end 0.105328 -0.198992)
      (stroke (width 0.1) (type solid)) (layer "F.SilkS"))
    (fp_line (start -0.094672 0.201008) (end -0.094672 -0.198992)
      (stroke (width 0.1) (type solid)) (layer "F.SilkS"))
    (fp_line (start 0.105328 0.001008) (end 0.24 0.001)
      (stroke (width 0.1) (type solid)) (layer "F.SilkS"))
    (fp_line (start 0.105328 0.201008) (end -0.094672 0.001008)
      (stroke (width 0.1) (type solid)) (layer "F.SilkS"))
    (fp_line (start 0.105328 0.201008) (end 0.105328 -0.198992)
      (stroke (width 0.1) (type solid)) (layer "F.SilkS"))
    (fp_line (start 0.22 -0.35) (end -0.22 -0.35)
      (stroke (width 0.15) (type solid)) (layer "F.SilkS"))
    (fp_line (start 0.22 0.35) (end -0.22 0.35)
      (stroke (width 0.15) (type solid)) (layer "F.SilkS"))
    (fp_rect (start 1.25 0.65) (end -1.25 -0.65)
      (stroke (width 0.05) (type solid)) (fill none) (layer "F.CrtYd"))
    (fp_line (start -0.199 -0.202) (end -0.199 0.1)
      (stroke (width 0.15) (type solid)) (layer "F.Fab"))
    (fp_line (start -0.199 0) (end -0.597 0)
      (stroke (width 0.15) (type solid)) (layer "F.Fab"))
    (fp_line (start -0.199 0.2) (end -0.199 0.1)
      (stroke (width 0.15) (type solid)) (layer "F.Fab"))
    (fp_line (start -0.101 0) (end 0.201 0.2)
      (stroke (width 0.15) (type solid)) (layer "F.Fab"))
    (fp_line (start 0.201 -0.202) (end -0.101 0)
      (stroke (width 0.15) (type solid)) (layer "F.Fab"))
    (fp_line (start 0.201 0) (end 0.201 -0.202)
      (stroke (width 0.15) (type solid)) (layer "F.Fab"))
    (fp_line (start 0.201 0.2) (end 0.201 0)
      (stroke (width 0.15) (type solid)) (layer "F.Fab"))
    (fp_line (start 0.599 0) (end 0.201 0)
      (stroke (width 0.15) (type solid)) (layer "F.Fab"))
    (fp_rect (start 0.848 0.4) (end -0.85 -0.402)
      (stroke (width 0.15) (type solid)) (fill none) (layer "F.Fab"))
    (pad "1" smd roundrect (at -0.7 0) (size 0.8 1) (layers "F.Cu" "F.Paste" "F.Mask") (roundrect_rratio 0.2)
      (net 2 "VCC3V3") (pinfunction "C") (pintype "passive"))
    (pad "2" smd roundrect (at 0.7 0) (size 0.8 1) (layers "F.Cu" "F.Paste" "F.Mask") (roundrect_rratio 0.2)
      (net 344 "Net-(D10-A)") (pinfunction "A") (pintype "passive"))
  )
	(footprint "antmicro-footprints:LED_0603_1608Metric_G" (layer "F.Cu")
    (at 65.5 90.816664 180)
    (descr "LED SMD 0603 Green")
    (tags "LED SMD 0603 Green")
    (property "Author" "Antmicro")
    (property "Color" "Green")
    (property "License" "Apache-2.0")
    (property "MPN" "LG L29K-G2J1-24-Z")
    (property "Manufacturer" "OSRAM")
    (property "Sheetfile" "power-supply.kicad_sch")
    (property "Sheetname" "Power supply")
    (property "ki_description" "LED, Green, SMD, 0603, 20 mA, 1.7 V, 570 nm")
    (property "ki_keywords" "SMT, DIODE, SEMICONDUCTOR, LED")
    (attr smd)
    (fp_text reference "D11" (at 1.8 -0.283336 90) (layer "F.SilkS")
        (effects (font (size 0.7 0.7) (thickness 0.127)))
    )
    (fp_text value "LED_G_0603_LG_L29K-G2J1-24-Z" (at 0 1.77) (layer "F.Fab")
        (effects (font (size 1 1) (thickness 0.15)))
    )
    (fp_text user "${REFERENCE}" (at -1.4224 5.999 180) (layer "F.Fab") hide
        (effects (font (size 0.7 0.7) (thickness 0.15)) (justify left bottom))
    )
    (fp_text user "Author: Antmicro" (at -1.4224 4.799 180) (layer "F.Fab") hide
        (effects (font (size 0.7 0.7) (thickness 0.15)) (justify left bottom))
    )
    (fp_text user "License: Apache-2.0" (at -1.4224 3.599 180) (layer "F.Fab") hide
        (effects (font (size 0.7 0.7) (thickness 0.15)) (justify left bottom))
    )
    (fp_line (start -1.18 -0.319) (end -1.18 0.321)
      (stroke (width 0.15) (type solid)) (layer "F.SilkS"))
    (fp_line (start -0.094672 0.001008) (end -0.24 0.001008)
      (stroke (width 0.1) (type solid)) (layer "F.SilkS"))
    (fp_line (start -0.094672 0.001008) (end 0.105328 -0.198992)
      (stroke (width 0.1) (type solid)) (layer "F.SilkS"))
    (fp_line (start -0.094672 0.201008) (end -0.094672 -0.198992)
      (stroke (width 0.1) (type solid)) (layer "F.SilkS"))
    (fp_line (start 0.105328 0.001008) (end 0.24 0.001)
      (stroke (width 0.1) (type solid)) (layer "F.SilkS"))
    (fp_line (start 0.105328 0.201008) (end -0.094672 0.001008)
      (stroke (width 0.1) (type solid)) (layer "F.SilkS"))
    (fp_line (start 0.105328 0.201008) (end 0.105328 -0.198992)
      (stroke (width 0.1) (type solid)) (layer "F.SilkS"))
    (fp_line (start 0.22 -0.35) (end -0.22 -0.35)
      (stroke (width 0.15) (type solid)) (layer "F.SilkS"))
    (fp_line (start 0.22 0.35) (end -0.22 0.35)
      (stroke (width 0.15) (type solid)) (layer "F.SilkS"))
    (fp_rect (start 1.25 0.65) (end -1.25 -0.65)
      (stroke (width 0.05) (type solid)) (fill none) (layer "F.CrtYd"))
    (fp_line (start -0.199 -0.202) (end -0.199 0.1)
      (stroke (width 0.15) (type solid)) (layer "F.Fab"))
    (fp_line (start -0.199 0) (end -0.597 0)
      (stroke (width 0.15) (type solid)) (layer "F.Fab"))
    (fp_line (start -0.199 0.2) (end -0.199 0.1)
      (stroke (width 0.15) (type solid)) (layer "F.Fab"))
    (fp_line (start -0.101 0) (end 0.201 0.2)
      (stroke (width 0.15) (type solid)) (layer "F.Fab"))
    (fp_line (start 0.201 -0.202) (end -0.101 0)
      (stroke (width 0.15) (type solid)) (layer "F.Fab"))
    (fp_line (start 0.201 0) (end 0.201 -0.202)
      (stroke (width 0.15) (type solid)) (layer "F.Fab"))
    (fp_line (start 0.201 0.2) (end 0.201 0)
      (stroke (width 0.15) (type solid)) (layer "F.Fab"))
    (fp_line (start 0.599 0) (end 0.201 0)
      (stroke (width 0.15) (type solid)) (layer "F.Fab"))
    (fp_rect (start 0.848 0.4) (end -0.85 -0.402)
      (stroke (width 0.15) (type solid)) (fill none) (layer "F.Fab"))
    (pad "1" smd roundrect (at -0.7 0) (size 0.8 1) (layers "F.Cu" "F.Paste" "F.Mask") (roundrect_rratio 0.2)
      (net 2 "VCC3V3") (pinfunction "C") (pintype "passive"))
    (pad "2" smd roundrect (at 0.7 0) (size 0.8 1) (layers "F.Cu" "F.Paste" "F.Mask") (roundrect_rratio 0.2)
      (net 345 "Net-(D11-A)") (pinfunction "A") (pintype "passive"))
  )
)
